(kicad_pcb
	(version 20241229)
	(generator "pcbnew")
	(generator_version "9.0")
	(general
		(thickness 1.61)
		(legacy_teardrops no)
	)
	(paper "A3")
	(title_block
		(title "RDIMM DDR5 Tester")
		(date "2026-05-21")
		(rev "2.2.0")
		(company "Antmicro")
		(comment 9 "footprint 109 of 796 (J2), pads 88-173 of 291")
	)
	(layers
		(0 "F.Cu" signal)
		(4 "In1.Cu" power)
		(6 "In2.Cu" mixed)
		(8 "In3.Cu" power)
		(10 "In4.Cu" mixed)
		(12 "In5.Cu" power)
		(14 "In6.Cu" mixed)
		(16 "In7.Cu" power)
		(18 "In8.Cu" power)
		(20 "In9.Cu" mixed)
		(22 "In10.Cu" power)
		(2 "B.Cu" signal)
		(9 "F.Adhes" user "F.Adhesive")
		(11 "B.Adhes" user "B.Adhesive")
		(13 "F.Paste" user)
		(15 "B.Paste" user)
		(5 "F.SilkS" user "F.Silkscreen")
		(7 "B.SilkS" user "B.Silkscreen")
		(1 "F.Mask" user)
		(3 "B.Mask" user)
		(17 "Dwgs.User" user "User.Drawings")
		(19 "Cmts.User" user "User.Comments")
		(21 "Eco1.User" user "User.Eco1")
		(23 "Eco2.User" user "User.Eco2")
		(25 "Edge.Cuts" user)
		(27 "Margin" user)
		(31 "F.CrtYd" user "F.Courtyard")
		(29 "B.CrtYd" user "B.Courtyard")
		(35 "F.Fab" user)
		(33 "B.Fab" user)
	)
	(footprint "antmicro-footprints:Bus_DDR5_Socket_Amphenol_DDR504111002KQ"
		(layer "F.Cu")
		(at 188.325 108.297 180)
		(descr "DIMM Connectors DDR5 SMD 288P")
		(property "Reference" "J2"
			(at 67.825 3.797 0)
			(layer "F.SilkS")
			(effects
				(font
					(size 0.7 0.7)
					(thickness 0.15)
				)
				(justify right bottom)
			)
		)
		(property "Value" "Bus_DDR5_DDR504111002KQ"
			(at 0 4.2 0)
			(layer "F.Fab")
			(effects
				(font
					(size 0.7 0.7)
					(thickness 0.15)
				)
				(justify right bottom)
			)
		)
		(property "Datasheet" "https://www.amphenol-icc.com/ddr5-smt-ddr504111002kq.html"
			(at 0 0 180)
			(layer "F.Fab")
			(hide yes)
			(effects
				(font
					(size 1.27 1.27)
					(thickness 0.15)
				)
			)
		)
		(property "Manufacturer" "Amphenol"
			(at 0 0 180)
			(unlocked yes)
			(layer "F.Fab")
			(hide yes)
			(effects
				(font
					(size 1 1)
					(thickness 0.15)
				)
			)
		)
		(property "MPN" "DDR504111002KQ"
			(at 0 0 180)
			(unlocked yes)
			(layer "F.Fab")
			(hide yes)
			(effects
				(font
					(size 1 1)
					(thickness 0.15)
				)
			)
		)
		(property "Author" "Antmicro"
			(at 0 0 180)
			(unlocked yes)
			(layer "F.Fab")
			(hide yes)
			(effects
				(font
					(size 1 1)
					(thickness 0.15)
				)
			)
		)
		(property "License" "Apache-2.0"
			(at 0 0 180)
			(unlocked yes)
			(layer "F.Fab")
			(hide yes)
			(effects
				(font
					(size 1 1)
					(thickness 0.15)
				)
			)
		)
		(sheetname "/DDR5 RDIMM/")
		(sheetfile "ddr5-rdimm.kicad_sch")
		(attr smd)
		(pad "88" smd rect
			(at 15.723 2.297 270)
			(size 1.8 0.57)
			(layers "F.Cu" "F.Mask" "F.Paste")
			(net 1 "GND")
			(pinfunction "VSS")
			(pintype "passive")
		)
		(pad "89" smd rect
			(at 16.574 2.297 270)
			(size 1.8 0.57)
			(layers "F.Cu" "F.Mask" "F.Paste")
			(net 99 "/DDR5 RDIMM/B.CB4")
			(pinfunction "CB4_B")
			(pintype "input")
		)
		(pad "90" smd rect
			(at 17.425 2.297 270)
			(size 1.8 0.57)
			(layers "F.Cu" "F.Mask" "F.Paste")
			(net 1 "GND")
			(pinfunction "VSS")
			(pintype "passive")
		)
		(pad "91" smd rect
			(at 18.274 2.297 270)
			(size 1.8 0.57)
			(layers "F.Cu" "F.Mask" "F.Paste")
			(net 100 "/DDR5 RDIMM/B.CB5")
			(pinfunction "CB5_B")
			(pintype "input")
		)
		(pad "92" smd rect
			(at 19.123 2.297 270)
			(size 1.8 0.57)
			(layers "F.Cu" "F.Mask" "F.Paste")
			(net 1 "GND")
			(pinfunction "VSS")
			(pintype "passive")
		)
		(pad "93" smd rect
			(at 19.975 2.297 270)
			(size 1.8 0.57)
			(layers "F.Cu" "F.Mask" "F.Paste")
			(net 126 "/DDR5 RDIMM/B.DQS9_P")
			(pinfunction "DQS9_B_T")
			(pintype "input")
		)
		(pad "94" smd rect
			(at 20.824 2.297 270)
			(size 1.8 0.57)
			(layers "F.Cu" "F.Mask" "F.Paste")
			(net 127 "/DDR5 RDIMM/B.DQS9_N")
			(pinfunction "DQS9_B_C")
			(pintype "input")
		)
		(pad "95" smd rect
			(at 21.675 2.297 270)
			(size 1.8 0.57)
			(layers "F.Cu" "F.Mask" "F.Paste")
			(net 1 "GND")
			(pinfunction "VSS")
			(pintype "passive")
		)
		(pad "96" smd rect
			(at 22.524 2.297 270)
			(size 1.8 0.57)
			(layers "F.Cu" "F.Mask" "F.Paste")
			(net 103 "/DDR5 RDIMM/B.CB0")
			(pinfunction "CB0_B")
			(pintype "input")
		)
		(pad "97" smd rect
			(at 23.373 2.297 270)
			(size 1.8 0.57)
			(layers "F.Cu" "F.Mask" "F.Paste")
			(net 1 "GND")
			(pinfunction "VSS")
			(pintype "passive")
		)
		(pad "98" smd rect
			(at 24.225 2.297 270)
			(size 1.8 0.57)
			(layers "F.Cu" "F.Mask" "F.Paste")
			(net 105 "/DDR5 RDIMM/B.CB1")
			(pinfunction "CB1_B")
			(pintype "input")
		)
		(pad "99" smd rect
			(at 25.074 2.297 270)
			(size 1.8 0.57)
			(layers "F.Cu" "F.Mask" "F.Paste")
			(net 1 "GND")
			(pinfunction "VSS")
			(pintype "passive")
		)
		(pad "100" smd rect
			(at 25.925 2.297 270)
			(size 1.8 0.57)
			(layers "F.Cu" "F.Mask" "F.Paste")
			(net 106 "/DDR5 RDIMM/B.DQ0")
			(pinfunction "DQ0_B")
			(pintype "input")
		)
		(pad "101" smd rect
			(at 26.774 2.297 270)
			(size 1.8 0.57)
			(layers "F.Cu" "F.Mask" "F.Paste")
			(net 1 "GND")
			(pinfunction "VSS")
			(pintype "passive")
		)
		(pad "102" smd rect
			(at 27.623 2.297 270)
			(size 1.8 0.57)
			(layers "F.Cu" "F.Mask" "F.Paste")
			(net 107 "/DDR5 RDIMM/B.DQ1")
			(pinfunction "DQ1_B")
			(pintype "input")
		)
		(pad "103" smd rect
			(at 28.475 2.297 270)
			(size 1.8 0.57)
			(layers "F.Cu" "F.Mask" "F.Paste")
			(net 1 "GND")
			(pinfunction "VSS")
			(pintype "passive")
		)
		(pad "104" smd rect
			(at 29.324 2.297 270)
			(size 1.8 0.57)
			(layers "F.Cu" "F.Mask" "F.Paste")
			(net 132 "/DDR5 RDIMM/B.DQS0_P")
			(pinfunction "DQS0_B_T")
			(pintype "input")
		)
		(pad "105" smd rect
			(at 30.175 2.297 270)
			(size 1.8 0.57)
			(layers "F.Cu" "F.Mask" "F.Paste")
			(net 133 "/DDR5 RDIMM/B.DQS0_N")
			(pinfunction "DQS0_B_C")
			(pintype "input")
		)
		(pad "106" smd rect
			(at 31.024 2.297 270)
			(size 1.8 0.57)
			(layers "F.Cu" "F.Mask" "F.Paste")
			(net 1 "GND")
			(pinfunction "VSS")
			(pintype "passive")
		)
		(pad "107" smd rect
			(at 31.873 2.297 270)
			(size 1.8 0.57)
			(layers "F.Cu" "F.Mask" "F.Paste")
			(net 110 "/DDR5 RDIMM/B.DQ4")
			(pinfunction "DQ4_B")
			(pintype "input")
		)
		(pad "108" smd rect
			(at 32.725 2.297 270)
			(size 1.8 0.57)
			(layers "F.Cu" "F.Mask" "F.Paste")
			(net 1 "GND")
			(pinfunction "VSS")
			(pintype "passive")
		)
		(pad "109" smd rect
			(at 33.575 2.297 270)
			(size 1.8 0.57)
			(layers "F.Cu" "F.Mask" "F.Paste")
			(net 111 "/DDR5 RDIMM/B.DQ5")
			(pinfunction "DQ5_B")
			(pintype "input")
		)
		(pad "110" smd rect
			(at 34.423 2.297 270)
			(size 1.8 0.57)
			(layers "F.Cu" "F.Mask" "F.Paste")
			(net 1 "GND")
			(pinfunction "VSS")
			(pintype "passive")
		)
		(pad "111" smd rect
			(at 35.274 2.297 270)
			(size 1.8 0.57)
			(layers "F.Cu" "F.Mask" "F.Paste")
			(net 112 "/DDR5 RDIMM/B.DQ8")
			(pinfunction "DQ8_B")
			(pintype "input")
		)
		(pad "112" smd rect
			(at 36.124 2.297 270)
			(size 1.8 0.57)
			(layers "F.Cu" "F.Mask" "F.Paste")
			(net 1 "GND")
			(pinfunction "VSS")
			(pintype "passive")
		)
		(pad "113" smd rect
			(at 36.975 2.297 270)
			(size 1.8 0.57)
			(layers "F.Cu" "F.Mask" "F.Paste")
			(net 113 "/DDR5 RDIMM/B.DQ9")
			(pinfunction "DQ9_B")
			(pintype "input")
		)
		(pad "114" smd rect
			(at 37.825 2.297 270)
			(size 1.8 0.57)
			(layers "F.Cu" "F.Mask" "F.Paste")
			(net 1 "GND")
			(pinfunction "VSS")
			(pintype "passive")
		)
		(pad "115" smd rect
			(at 38.673 2.297 270)
			(size 1.8 0.57)
			(layers "F.Cu" "F.Mask" "F.Paste")
			(net 141 "/DDR5 RDIMM/B.DQS1_P")
			(pinfunction "DQS1_B_T")
			(pintype "input")
		)
		(pad "116" smd rect
			(at 39.524 2.297 270)
			(size 1.8 0.57)
			(layers "F.Cu" "F.Mask" "F.Paste")
			(net 142 "/DDR5 RDIMM/B.DQS1_N")
			(pinfunction "DQS1_B_C")
			(pintype "input")
		)
		(pad "117" smd rect
			(at 40.374 2.297 270)
			(size 1.8 0.57)
			(layers "F.Cu" "F.Mask" "F.Paste")
			(net 1 "GND")
			(pinfunction "VSS")
			(pintype "passive")
		)
		(pad "118" smd rect
			(at 41.225 2.297 270)
			(size 1.8 0.57)
			(layers "F.Cu" "F.Mask" "F.Paste")
			(net 116 "/DDR5 RDIMM/B.DQ12")
			(pinfunction "DQ12_B")
			(pintype "input")
		)
		(pad "119" smd rect
			(at 42.075 2.297 270)
			(size 1.8 0.57)
			(layers "F.Cu" "F.Mask" "F.Paste")
			(net 1 "GND")
			(pinfunction "VSS")
			(pintype "passive")
		)
		(pad "120" smd rect
			(at 42.923 2.297 270)
			(size 1.8 0.57)
			(layers "F.Cu" "F.Mask" "F.Paste")
			(net 117 "/DDR5 RDIMM/B.DQ13")
			(pinfunction "DQ13_B")
			(pintype "input")
		)
		(pad "121" smd rect
			(at 43.773 2.297 270)
			(size 1.8 0.57)
			(layers "F.Cu" "F.Mask" "F.Paste")
			(net 1 "GND")
			(pinfunction "VSS")
			(pintype "passive")
		)
		(pad "122" smd rect
			(at 44.624 2.297 270)
			(size 1.8 0.57)
			(layers "F.Cu" "F.Mask" "F.Paste")
			(net 118 "/DDR5 RDIMM/B.DQ16")
			(pinfunction "DQ16_B")
			(pintype "input")
		)
		(pad "123" smd rect
			(at 45.475 2.297 270)
			(size 1.8 0.57)
			(layers "F.Cu" "F.Mask" "F.Paste")
			(net 1 "GND")
			(pinfunction "VSS")
			(pintype "passive")
		)
		(pad "124" smd rect
			(at 46.325 2.297 270)
			(size 1.8 0.57)
			(layers "F.Cu" "F.Mask" "F.Paste")
			(net 119 "/DDR5 RDIMM/B.DQ17")
			(pinfunction "DQ17_B")
			(pintype "input")
		)
		(pad "125" smd rect
			(at 47.173 2.297 270)
			(size 1.8 0.57)
			(layers "F.Cu" "F.Mask" "F.Paste")
			(net 1 "GND")
			(pinfunction "VSS")
			(pintype "passive")
		)
		(pad "126" smd rect
			(at 48.023 2.297 270)
			(size 1.8 0.57)
			(layers "F.Cu" "F.Mask" "F.Paste")
			(net 147 "/DDR5 RDIMM/B.DQS2_P")
			(pinfunction "DQS2_B_T")
			(pintype "input")
		)
		(pad "127" smd rect
			(at 48.874 2.297 270)
			(size 1.8 0.57)
			(layers "F.Cu" "F.Mask" "F.Paste")
			(net 148 "/DDR5 RDIMM/B.DQS2_N")
			(pinfunction "DQS2_B_C")
			(pintype "input")
		)
		(pad "128" smd rect
			(at 49.725 2.297 270)
			(size 1.8 0.57)
			(layers "F.Cu" "F.Mask" "F.Paste")
			(net 1 "GND")
			(pinfunction "VSS")
			(pintype "passive")
		)
		(pad "129" smd rect
			(at 50.575 2.297 270)
			(size 1.8 0.57)
			(layers "F.Cu" "F.Mask" "F.Paste")
			(net 122 "/DDR5 RDIMM/B.DQ20")
			(pinfunction "DQ20_B")
			(pintype "input")
		)
		(pad "130" smd rect
			(at 51.423 2.297 270)
			(size 1.8 0.57)
			(layers "F.Cu" "F.Mask" "F.Paste")
			(net 1 "GND")
			(pinfunction "VSS")
			(pintype "passive")
		)
		(pad "131" smd rect
			(at 52.273 2.297 270)
			(size 1.8 0.57)
			(layers "F.Cu" "F.Mask" "F.Paste")
			(net 123 "/DDR5 RDIMM/B.DQ21")
			(pinfunction "DQ21_B")
			(pintype "input")
		)
		(pad "132" smd rect
			(at 53.124 2.297 270)
			(size 1.8 0.57)
			(layers "F.Cu" "F.Mask" "F.Paste")
			(net 1 "GND")
			(pinfunction "VSS")
			(pintype "passive")
		)
		(pad "133" smd rect
			(at 53.975 2.297 270)
			(size 1.8 0.57)
			(layers "F.Cu" "F.Mask" "F.Paste")
			(net 124 "/DDR5 RDIMM/B.DQ24")
			(pinfunction "DQ24_B")
			(pintype "input")
		)
		(pad "134" smd rect
			(at 54.825 2.297 270)
			(size 1.8 0.57)
			(layers "F.Cu" "F.Mask" "F.Paste")
			(net 1 "GND")
			(pinfunction "VSS")
			(pintype "passive")
		)
		(pad "135" smd rect
			(at 55.673 2.297 270)
			(size 1.8 0.57)
			(layers "F.Cu" "F.Mask" "F.Paste")
			(net 125 "/DDR5 RDIMM/B.DQ25")
			(pinfunction "DQ25_B")
			(pintype "input")
		)
		(pad "136" smd rect
			(at 56.523 2.297 270)
			(size 1.8 0.57)
			(layers "F.Cu" "F.Mask" "F.Paste")
			(net 1 "GND")
			(pinfunction "VSS")
			(pintype "passive")
		)
		(pad "137" smd rect
			(at 57.374 2.297 270)
			(size 1.8 0.57)
			(layers "F.Cu" "F.Mask" "F.Paste")
			(net 156 "/DDR5 RDIMM/B.DQS3_P")
			(pinfunction "DQS3_B_T")
			(pintype "input")
		)
		(pad "138" smd rect
			(at 58.225 2.297 270)
			(size 1.8 0.57)
			(layers "F.Cu" "F.Mask" "F.Paste")
			(net 161 "/DDR5 RDIMM/B.DQS3_N")
			(pinfunction "DQS3_B_C")
			(pintype "input")
		)
		(pad "139" smd rect
			(at 59.075 2.297 270)
			(size 1.8 0.57)
			(layers "F.Cu" "F.Mask" "F.Paste")
			(net 1 "GND")
			(pinfunction "VSS")
			(pintype "passive")
		)
		(pad "140" smd rect
			(at 59.923 2.297 270)
			(size 1.8 0.57)
			(layers "F.Cu" "F.Mask" "F.Paste")
			(net 128 "/DDR5 RDIMM/B.DQ28")
			(pinfunction "DQ28_B")
			(pintype "input")
		)
		(pad "141" smd rect
			(at 60.773 2.297 270)
			(size 1.8 0.57)
			(layers "F.Cu" "F.Mask" "F.Paste")
			(net 1 "GND")
			(pinfunction "VSS")
			(pintype "passive")
		)
		(pad "142" smd rect
			(at 61.624 2.297 270)
			(size 1.8 0.57)
			(layers "F.Cu" "F.Mask" "F.Paste")
			(net 129 "/DDR5 RDIMM/B.DQ29")
			(pinfunction "DQ29_B")
			(pintype "input")
		)
		(pad "143" smd rect
			(at 62.475 2.297 270)
			(size 1.8 0.57)
			(layers "F.Cu" "F.Mask" "F.Paste")
			(net 1 "GND")
			(pinfunction "VSS")
			(pintype "passive")
		)
		(pad "144" smd rect
			(at 63.325 2.297 270)
			(size 1.8 0.57)
			(layers "F.Cu" "F.Mask" "F.Paste")
			(net 309 "unconnected-(J2B-RFU-Pad144)")
			(pinfunction "RFU")
			(pintype "no_connect")
		)
		(pad "145" smd rect
			(at -63.326 -2.301 270)
			(size 1.8 0.57)
			(layers "F.Cu" "F.Mask" "F.Paste")
			(net 802 "/DDR5 RDIMM/VIN_BULK")
			(pinfunction "VIN_BULK")
			(pintype "passive")
		)
		(pad "146" smd rect
			(at -62.476 -2.301 270)
			(size 1.8 0.57)
			(layers "F.Cu" "F.Mask" "F.Paste")
			(net 802 "/DDR5 RDIMM/VIN_BULK")
			(pinfunction "VIN_BULK")
			(pintype "passive")
		)
		(pad "147" smd rect
			(at -61.625 -2.301 270)
			(size 1.8 0.57)
			(layers "F.Cu" "F.Mask" "F.Paste")
			(net 602 "/DDR5 RDIMM/CTRL.PWR_GOOD")
			(pinfunction "PCAMP")
			(pintype "input")
		)
		(pad "148" smd rect
			(at -60.775 -2.301 270)
			(size 1.8 0.57)
			(layers "F.Cu" "F.Mask" "F.Paste")
			(net 461 "/DDR5 RDIMM/HSA")
			(pinfunction "HSA")
			(pintype "input")
		)
		(pad "149" smd rect
			(at -59.926 -2.301 270)
			(size 1.8 0.57)
			(layers "F.Cu" "F.Mask" "F.Paste")
			(net 310 "unconnected-(J2B-RFU-Pad149)")
			(pinfunction "RFU")
			(pintype "no_connect")
		)
		(pad "150" smd rect
			(at -59.076 -2.301 270)
			(size 1.8 0.57)
			(layers "F.Cu" "F.Mask" "F.Paste")
			(net 361 "unconnected-(J2B-RFU-Pad150)")
			(pinfunction "RFU")
			(pintype "no_connect")
		)
		(pad "151" smd rect
			(at -58.226 -2.301 270)
			(size 1.8 0.57)
			(layers "F.Cu" "F.Mask" "F.Paste")
			(net 1 "GND")
			(pinfunction "VSS")
			(pintype "passive")
		)
		(pad "152" smd rect
			(at -57.375 -2.301 270)
			(size 1.8 0.57)
			(layers "F.Cu" "F.Mask" "F.Paste")
			(net 130 "/DDR5 RDIMM/A.DQ2")
			(pinfunction "DQ2_A")
			(pintype "input")
		)
		(pad "153" smd rect
			(at -56.525 -2.301 270)
			(size 1.8 0.57)
			(layers "F.Cu" "F.Mask" "F.Paste")
			(net 1 "GND")
			(pinfunction "VSS")
			(pintype "passive")
		)
		(pad "154" smd rect
			(at -55.676 -2.301 270)
			(size 1.8 0.57)
			(layers "F.Cu" "F.Mask" "F.Paste")
			(net 131 "/DDR5 RDIMM/A.DQ3")
			(pinfunction "DQ3_A")
			(pintype "input")
		)
		(pad "155" smd rect
			(at -54.826 -2.301 270)
			(size 1.8 0.57)
			(layers "F.Cu" "F.Mask" "F.Paste")
			(net 1 "GND")
			(pinfunction "VSS")
			(pintype "passive")
		)
		(pad "156" smd rect
			(at -53.976 -2.301 270)
			(size 1.8 0.57)
			(layers "F.Cu" "F.Mask" "F.Paste")
			(net 177 "/DDR5 RDIMM/A.DQS5_N")
			(pinfunction "DQS5_A_C")
			(pintype "input")
		)
		(pad "157" smd rect
			(at -53.125 -2.301 270)
			(size 1.8 0.57)
			(layers "F.Cu" "F.Mask" "F.Paste")
			(net 178 "/DDR5 RDIMM/A.DQS5_P")
			(pinfunction "DQS5_A_T")
			(pintype "input")
		)
		(pad "158" smd rect
			(at -52.275 -2.301 270)
			(size 1.8 0.57)
			(layers "F.Cu" "F.Mask" "F.Paste")
			(net 1 "GND")
			(pinfunction "VSS")
			(pintype "passive")
		)
		(pad "159" smd rect
			(at -51.426 -2.301 270)
			(size 1.8 0.57)
			(layers "F.Cu" "F.Mask" "F.Paste")
			(net 134 "/DDR5 RDIMM/A.DQ6")
			(pinfunction "DQ6_A")
			(pintype "input")
		)
		(pad "160" smd rect
			(at -50.576 -2.301 270)
			(size 1.8 0.57)
			(layers "F.Cu" "F.Mask" "F.Paste")
			(net 1 "GND")
			(pinfunction "VSS")
			(pintype "passive")
		)
		(pad "161" smd rect
			(at -49.726 -2.301 270)
			(size 1.8 0.57)
			(layers "F.Cu" "F.Mask" "F.Paste")
			(net 135 "/DDR5 RDIMM/A.DQ7")
			(pinfunction "DQ7_A")
			(pintype "input")
		)
		(pad "162" smd rect
			(at -48.875 -2.301 270)
			(size 1.8 0.57)
			(layers "F.Cu" "F.Mask" "F.Paste")
			(net 1 "GND")
			(pinfunction "VSS")
			(pintype "passive")
		)
		(pad "163" smd rect
			(at -48.025 -2.301 270)
			(size 1.8 0.57)
			(layers "F.Cu" "F.Mask" "F.Paste")
			(net 136 "/DDR5 RDIMM/A.DQ10")
			(pinfunction "DQ10_A")
			(pintype "input")
		)
		(pad "164" smd rect
			(at -47.176 -2.301 270)
			(size 1.8 0.57)
			(layers "F.Cu" "F.Mask" "F.Paste")
			(net 1 "GND")
			(pinfunction "VSS")
			(pintype "passive")
		)
		(pad "165" smd rect
			(at -46.326 -2.301 270)
			(size 1.8 0.57)
			(layers "F.Cu" "F.Mask" "F.Paste")
			(net 140 "/DDR5 RDIMM/A.DQ11")
			(pinfunction "DQ11_A")
			(pintype "input")
		)
		(pad "166" smd rect
			(at -45.476 -2.301 270)
			(size 1.8 0.57)
			(layers "F.Cu" "F.Mask" "F.Paste")
			(net 1 "GND")
			(pinfunction "VSS")
			(pintype "passive")
		)
		(pad "167" smd rect
			(at -44.625 -2.301 270)
			(size 1.8 0.57)
			(layers "F.Cu" "F.Mask" "F.Paste")
			(net 181 "/DDR5 RDIMM/A.DQS6_N")
			(pinfunction "DQS6_A_C")
			(pintype "input")
		)
		(pad "168" smd rect
			(at -43.775 -2.301 270)
			(size 1.8 0.57)
			(layers "F.Cu" "F.Mask" "F.Paste")
			(net 182 "/DDR5 RDIMM/A.DQS6_P")
			(pinfunction "DQS6_A_T")
			(pintype "input")
		)
		(pad "169" smd rect
			(at -42.926 -2.301 270)
			(size 1.8 0.57)
			(layers "F.Cu" "F.Mask" "F.Paste")
			(net 1 "GND")
			(pinfunction "VSS")
			(pintype "passive")
		)
		(pad "170" smd rect
			(at -42.076 -2.301 270)
			(size 1.8 0.57)
			(layers "F.Cu" "F.Mask" "F.Paste")
			(net 143 "/DDR5 RDIMM/A.DQ14")
			(pinfunction "DQ14_A")
			(pintype "input")
		)
		(pad "171" smd rect
			(at -41.226 -2.301 270)
			(size 1.8 0.57)
			(layers "F.Cu" "F.Mask" "F.Paste")
			(net 1 "GND")
			(pinfunction "VSS")
			(pintype "passive")
		)
		(pad "172" smd rect
			(at -40.375 -2.301 270)
			(size 1.8 0.57)
			(layers "F.Cu" "F.Mask" "F.Paste")
			(net 144 "/DDR5 RDIMM/A.DQ15")
			(pinfunction "DQ15_A")
			(pintype "input")
		)
		(pad "173" smd rect
			(at -39.525 -2.301 270)
			(size 1.8 0.57)
			(layers "F.Cu" "F.Mask" "F.Paste")
			(net 1 "GND")
			(pinfunction "VSS")
			(pintype "passive")
		)
	)
)
